# BASEBOARD_FAB2 (Tioga Pass) — schematic netlist excerpt (pin names and nets, part order shuffled) for the footprints in the layout excerpt that follows; sources: Cadence DE-HDL packaged netlist, KiCad conversion of Wiwynn_Tioga_Pass_MB.brd

T1P34  TPAD-SE-2P-GP  pkg DISCRET-GA1  page 256 : \1\ = L10_50OHM_6INCH ; GND1 = GND
C4A9  CAP  1.0UF 16V 10% X6S  pkg 0402  page 222 : A = VR_PVTT_DEF_VREF ; B = GND
R4G16  RES  0.0 5% CHIP  pkg 0402  page 229 : A = PWRGD_PVDDQ_GHJ_R ; B = FM_PVTT_GHJ_EN_R

(kicad_pcb
	(version 20260206)
	(generator "pcbnew")
	(generator_version "10.0")
	(general
		(thickness 1.6)
		(legacy_teardrops no)
	)
	(paper "A4")
	(title_block
		(title "Wiwynn_Tioga_Pass_MB.brd")
		(comment 1 "Tioga Pass / footprints 1735-1737 of 4770")
	)
	(layers
		(0 "F.Cu" signal "TOP")
		(4 "In1.Cu" signal "L2GND")
		(6 "In2.Cu" signal "L3")
		(8 "In3.Cu" signal "L4GND")
		(10 "In4.Cu" signal "L5")
		(12 "In5.Cu" signal "L6GND")
		(14 "In6.Cu" signal "L7VCC")
		(16 "In7.Cu" signal "L8VCC")
		(18 "In8.Cu" signal "L9GND")
		(20 "In9.Cu" signal "L10")
		(22 "In10.Cu" signal "L11GND")
		(24 "In11.Cu" signal "L12")
		(26 "In12.Cu" signal "L13GND")
		(2 "B.Cu" signal "BOTTOM")
		(9 "F.Adhes" user "F.Adhesive")
		(11 "B.Adhes" user "B.Adhesive")
		(13 "F.Paste" user "Package Geometry/Pastemask Top")
		(15 "B.Paste" user "Package Geometry/Pastemask Bottom")
		(5 "F.SilkS" user "Ref Des/Silkscreen Top")
		(7 "B.SilkS" user "Ref Des/Silkscreen Bottom")
		(1 "F.Mask" user "Board Geometry/Soldermask Top")
		(3 "B.Mask" user "Board Geometry/Soldermask Bottom")
		(17 "Dwgs.User" user "User.Drawings")
		(19 "Cmts.User" user "User.Comments")
		(21 "Eco1.User" user "User.Eco1")
		(23 "Eco2.User" user "User.Eco2")
		(25 "Edge.Cuts" user "Board Geometry/Outline")
		(27 "Margin" user)
		(31 "F.CrtYd" user "Package Geometry/Place Bound Top")
		(29 "B.CrtYd" user "Package Geometry/Place Bound Bottom")
		(35 "F.Fab" user "Ref Des/Assembly Top")
		(33 "B.Fab" user "Ref Des/Assembly Bottom")
	)
	(footprint ""
		(layer "F.Cu")
		(at 180.594 -146.812)
		(property "Reference" "C4A9"
			(at 0 0 0)
			(layer "F.SilkS")
			(hide yes)
			(effects
				(font
					(size 1.27 1.27)
				)
			)
		)
		(property "Value" ""
			(at 0 0 0)
			(layer "F.Fab")
			(effects
				(font
					(size 1.27 1.27)
				)
			)
		)
		(duplicate_pad_numbers_are_jumpers no)
		(fp_rect
			(start 0.3048 -0.1016)
			(end -0.3048 0.9906)
			(stroke
				(width 0)
				(type default)
			)
			(fill no)
			(layer "F.CrtYd")
		)
		(fp_line
			(start -0.3048 -0.1016)
			(end -0.3048 0.9906)
			(stroke
				(width 0.1)
				(type default)
			)
			(layer "F.Fab")
		)
		(fp_line
			(start -0.3048 0.9906)
			(end 0.3048 0.9906)
			(stroke
				(width 0.1)
				(type default)
			)
			(layer "F.Fab")
		)
		(fp_line
			(start 0.3048 -0.1016)
			(end -0.3048 -0.1016)
			(stroke
				(width 0.1)
				(type default)
			)
			(layer "F.Fab")
		)
		(fp_line
			(start 0.3048 0.9906)
			(end 0.3048 -0.1016)
			(stroke
				(width 0.1)
				(type default)
			)
			(layer "F.Fab")
		)
		(pad "1" smd rect
			(at 0 0)
			(size 0.508 0.508)
			(layers "F.Cu" "F.Mask" "F.Paste")
			(net "VR_PVTT_DEF_VREF")
		)
		(pad "2" smd rect
			(at 0 0.889)
			(size 0.508 0.508)
			(layers "F.Cu" "F.Mask" "F.Paste")
			(net "GND")
		)
		(zone
			(layer "F.Cu")
			(hatch none 0.5)
			(connect_pads
				(clearance 0)
			)
			(min_thickness 0.25)
			(keepout
				(tracks not_allowed)
				(vias allowed)
				(pads allowed)
				(copperpour not_allowed)
				(footprints allowed)
			)
			(placement
				(enabled no)
				(sheetname "")
			)
			(fill
				(thermal_gap 0.5)
				(thermal_bridge_width 0.5)
				(island_removal_mode 0)
			)
			(polygon
				(pts
					(xy 180.848 -146.558) (xy 180.34 -146.558) (xy 180.34 -146.177) (xy 180.848 -146.177)
				)
			)
		)
		(zone
			(layer "F.Cu")
			(hatch none 0.5)
			(connect_pads
				(clearance 0)
			)
			(min_thickness 0.25)
			(keepout
				(tracks allowed)
				(vias not_allowed)
				(pads allowed)
				(copperpour not_allowed)
				(footprints allowed)
			)
			(placement
				(enabled no)
				(sheetname "")
			)
			(fill
				(thermal_gap 0.5)
				(thermal_bridge_width 0.5)
				(island_removal_mode 0)
			)
			(polygon
				(pts
					(xy 180.848 -146.558) (xy 180.34 -146.558) (xy 180.34 -146.177) (xy 180.848 -146.177)
				)
			)
		)
	)
	(footprint ""
		(layer "F.Cu")
		(at 24.257 13.2715 -90)
		(property "Reference" "T1P34"
			(at 0 0 270)
			(layer "F.SilkS")
			(hide yes)
			(effects
				(font
					(size 1.27 1.27)
				)
			)
		)
		(property "Value" "*"
			(at 0 -3.44805 270)
			(unlocked yes)
			(layer "F.Fab")
			(hide yes)
			(effects
				(font
					(size 0.889 0.889)
					(thickness 0.1524)
				)
			)
		)
		(property "Device Type" "TPAD-SE-2P-GP_DISCRET-GA1-TPADA"
			(at 0 -4.97205 270)
			(unlocked yes)
			(layer "F.Fab")
			(hide yes)
			(effects
				(font
					(size 0.889 0.889)
					(thickness 0.1524)
				)
			)
		)
		(duplicate_pad_numbers_are_jumpers no)
		(fp_line
			(start -1.016 2.286)
			(end -1.016 -2.286)
			(stroke
				(width 0.1524)
				(type default)
			)
			(layer "F.SilkS")
		)
		(fp_line
			(start 1.016 2.286)
			(end -1.016 2.286)
			(stroke
				(width 0.1524)
				(type default)
			)
			(layer "F.SilkS")
		)
		(fp_line
			(start -1.016 -2.286)
			(end 1.016 -2.286)
			(stroke
				(width 0.1524)
				(type default)
			)
			(layer "F.SilkS")
		)
		(fp_line
			(start 1.016 -2.286)
			(end 1.016 2.286)
			(stroke
				(width 0.1524)
				(type default)
			)
			(layer "F.SilkS")
		)
		(fp_rect
			(start -1.27 2.54)
			(end 1.27 -2.54)
			(stroke
				(width 0)
				(type default)
			)
			(fill no)
			(layer "F.CrtYd")
		)
		(fp_rect
			(start -1.27 2.54)
			(end 1.27 -2.54)
			(stroke
				(width 0)
				(type default)
			)
			(fill no)
			(layer "F.Fab")
		)
		(pad "1" thru_hole circle
			(at 0 -1.27 270)
			(size 1.524 1.524)
			(drill 0.9144)
			(layers "*.Cu" "*.Mask")
			(remove_unused_layers no)
			(net "L10_50OHM_6INCH")
			(clearance -0.0508)
			(thermal_gap 0.127)
			(padstack
				(mode front_inner_back)
				(layer "Inner"
					(shape circle)
					(size 1.1684 1.1684)
					(clearance 0.127)
				)
				(layer "B.Cu"
					(shape circle)
					(size 1.524 1.524)
					(clearance -0.0508)
				)
			)
		)
		(pad "GND1" thru_hole rect
			(at 0 1.27 270)
			(size 1.524 1.524)
			(drill 0.9144)
			(layers "*.Cu" "*.Mask")
			(remove_unused_layers no)
			(net "GND")
			(clearance -0.0508)
			(thermal_gap 0.127)
			(padstack
				(mode front_inner_back)
				(layer "Inner"
					(shape circle)
					(size 1.1684 1.1684)
					(clearance 0.127)
				)
				(layer "B.Cu"
					(shape rect)
					(size 1.524 1.524)
					(clearance -0.0508)
				)
			)
		)
	)
	(footprint ""
		(layer "F.Cu")
		(at 165.608 -6.477 90)
		(property "Reference" "R4G16"
			(at 0 0 90)
			(layer "F.SilkS")
			(hide yes)
			(effects
				(font
					(size 1.27 1.27)
				)
			)
		)
		(property "Value" ""
			(at 0 0 90)
			(layer "F.Fab")
			(effects
				(font
					(size 1.27 1.27)
				)
			)
		)
		(duplicate_pad_numbers_are_jumpers no)
		(fp_poly
			(pts
				(xy -0.2794 -0.1016) (xy 0.2794 -0.1016) (xy 0.2794 0.9906) (xy -0.2794 0.9906)
			)
			(stroke
				(width 0)
				(type default)
			)
			(fill no)
			(layer "F.CrtYd")
		)
		(fp_line
			(start 0.2794 -0.1016)
			(end -0.2794 -0.1016)
			(stroke
				(width 0.1)
				(type default)
			)
			(layer "F.Fab")
		)
		(fp_line
			(start -0.2794 -0.1016)
			(end -0.2794 0.9906)
			(stroke
				(width 0.1)
				(type default)
			)
			(layer "F.Fab")
		)
		(fp_line
			(start 0.2794 0.9906)
			(end 0.2794 -0.1016)
			(stroke
				(width 0.1)
				(type default)
			)
			(layer "F.Fab")
		)
		(fp_line
			(start -0.2794 0.9906)
			(end 0.2794 0.9906)
			(stroke
				(width 0.1)
				(type default)
			)
			(layer "F.Fab")
		)
		(pad "1" smd rect
			(at 0 0 90)
			(size 0.508 0.508)
			(layers "F.Cu" "F.Mask" "F.Paste")
			(net "PWRGD_PVDDQ_GHJ_R")
		)
		(pad "2" smd rect
			(at 0 0.889 90)
			(size 0.508 0.508)
			(layers "F.Cu" "F.Mask" "F.Paste")
			(net "FM_PVTT_GHJ_EN_R")
		)
		(zone
			(layer "F.Cu")
			(hatch none 0.5)
			(connect_pads
				(clearance 0)
			)
			(min_thickness 0.25)
			(keepout
				(tracks allowed)
				(vias not_allowed)
				(pads allowed)
				(copperpour not_allowed)
				(footprints allowed)
			)
			(placement
				(enabled no)
				(sheetname "")
			)
			(fill
				(thermal_gap 0.5)
				(thermal_bridge_width 0.5)
				(island_removal_mode 0)
			)
			(polygon
				(pts
					(xy 165.862 -6.223) (xy 165.862 -6.731) (xy 166.243 -6.731) (xy 166.243 -6.223)
				)
			)
		)
		(zone
			(layer "F.Cu")
			(hatch none 0.5)
			(connect_pads
				(clearance 0)
			)
			(min_thickness 0.25)
			(keepout
				(tracks not_allowed)
				(vias allowed)
				(pads allowed)
				(copperpour not_allowed)
				(footprints allowed)
			)
			(placement
				(enabled no)
				(sheetname "")
			)
			(fill
				(thermal_gap 0.5)
				(thermal_bridge_width 0.5)
				(island_removal_mode 0)
			)
			(polygon
				(pts
					(xy 166.243 -6.223) (xy 166.243 -6.731) (xy 165.862 -6.731) (xy 165.862 -6.223)
				)
			)
		)
	)
)
